# BASEBOARD_FAB2 (Tioga Pass) — schematic netlist excerpt (pin names and nets, part order shuffled) for the footprints in the layout excerpt that follows; sources: Cadence DE-HDL packaged netlist, KiCad conversion of Wiwynn_Tioga_Pass_MB.brd

T1P12  TPAD-DIFF-4P-GP  pkg DISCRET-GB3  page 256
  \1\  = L14_73OHM_6INCH_DP
  \2\  = L14_73OHM_6INCH_DN
  GND1  = GND
  GND2  = GND

C1D20  CAP  0.220UF 16V 10% X7R  pkg 0402  page 208 : A = VR_PVCCIN_CPU1_PH3_BOOT ; B = VR_PVCCIN_CPU1_PH3_PHASE

(kicad_pcb
	(version 20260206)
	(generator "pcbnew")
	(generator_version "10.0")
	(general
		(thickness 1.6)
		(legacy_teardrops no)
	)
	(paper "A4")
	(title_block
		(title "Wiwynn_Tioga_Pass_MB.brd")
		(comment 1 "Tioga Pass / footprints 1434-1435 of 4770")
	)
	(layers
		(0 "F.Cu" signal "TOP")
		(4 "In1.Cu" signal "L2GND")
		(6 "In2.Cu" signal "L3")
		(8 "In3.Cu" signal "L4GND")
		(10 "In4.Cu" signal "L5")
		(12 "In5.Cu" signal "L6GND")
		(14 "In6.Cu" signal "L7VCC")
		(16 "In7.Cu" signal "L8VCC")
		(18 "In8.Cu" signal "L9GND")
		(20 "In9.Cu" signal "L10")
		(22 "In10.Cu" signal "L11GND")
		(24 "In11.Cu" signal "L12")
		(26 "In12.Cu" signal "L13GND")
		(2 "B.Cu" signal "BOTTOM")
		(9 "F.Adhes" user "F.Adhesive")
		(11 "B.Adhes" user "B.Adhesive")
		(13 "F.Paste" user "Package Geometry/Pastemask Top")
		(15 "B.Paste" user "Package Geometry/Pastemask Bottom")
		(5 "F.SilkS" user "Ref Des/Silkscreen Top")
		(7 "B.SilkS" user "Ref Des/Silkscreen Bottom")
		(1 "F.Mask" user "Board Geometry/Soldermask Top")
		(3 "B.Mask" user "Board Geometry/Soldermask Bottom")
		(17 "Dwgs.User" user "User.Drawings")
		(19 "Cmts.User" user "User.Comments")
		(21 "Eco1.User" user "User.Eco1")
		(23 "Eco2.User" user "User.Eco2")
		(25 "Edge.Cuts" user "Board Geometry/Outline")
		(27 "Margin" user)
		(31 "F.CrtYd" user "Package Geometry/Place Bound Top")
		(29 "B.CrtYd" user "Package Geometry/Place Bound Bottom")
		(35 "F.Fab" user "Ref Des/Assembly Top")
		(33 "B.Fab" user "Ref Des/Assembly Bottom")
	)
	(footprint ""
		(layer "F.Cu")
		(at 142.810484 12.014454 -90)
		(property "Reference" "T1P12"
			(at 0 0 270)
			(layer "F.SilkS")
			(hide yes)
			(effects
				(font
					(size 1.27 1.27)
				)
			)
		)
		(property "Value" "*"
			(at -3.302 1.12395 270)
			(unlocked yes)
			(layer "F.Fab")
			(hide yes)
			(effects
				(font
					(size 0.889 0.889)
					(thickness 0.1524)
				)
			)
		)
		(property "Device Type" "TPAD-DIFF-4P-GP_DISCRET-GB3-TPA"
			(at -3.302 -0.40005 270)
			(unlocked yes)
			(layer "F.Fab")
			(hide yes)
			(effects
				(font
					(size 0.889 0.889)
					(thickness 0.1524)
				)
			)
		)
		(duplicate_pad_numbers_are_jumpers no)
		(fp_line
			(start -2.286 2.286)
			(end 2.286 2.286)
			(stroke
				(width 0.1524)
				(type default)
			)
			(layer "F.SilkS")
		)
		(fp_line
			(start 2.286 2.286)
			(end 2.286 -2.286)
			(stroke
				(width 0.1524)
				(type default)
			)
			(layer "F.SilkS")
		)
		(fp_line
			(start -2.286 -2.286)
			(end -2.286 2.286)
			(stroke
				(width 0.1524)
				(type default)
			)
			(layer "F.SilkS")
		)
		(fp_line
			(start 2.286 -2.286)
			(end -2.286 -2.286)
			(stroke
				(width 0.1524)
				(type default)
			)
			(layer "F.SilkS")
		)
		(fp_line
			(start -2.413 -2.413)
			(end -2.413 -1.143)
			(stroke
				(width 0.4064)
				(type default)
			)
			(layer "F.SilkS")
		)
		(fp_line
			(start -1.143 -2.413)
			(end -2.413 -2.413)
			(stroke
				(width 0.4064)
				(type default)
			)
			(layer "F.SilkS")
		)
		(fp_rect
			(start -2.54 2.54)
			(end 2.54 -2.54)
			(stroke
				(width 0)
				(type default)
			)
			(fill no)
			(layer "F.CrtYd")
		)
		(fp_rect
			(start -2.54 2.54)
			(end 2.54 -2.54)
			(stroke
				(width 0)
				(type default)
			)
			(fill no)
			(layer "F.Fab")
		)
		(pad "1" thru_hole circle
			(at -1.27 -1.27 270)
			(size 1.524 1.524)
			(drill 0.9144)
			(layers "*.Cu" "*.Mask")
			(remove_unused_layers no)
			(net "L14_73OHM_6INCH_DP")
			(clearance -0.0508)
			(thermal_gap 0.127)
			(padstack
				(mode front_inner_back)
				(layer "Inner"
					(shape circle)
					(size 1.1684 1.1684)
					(clearance 0.127)
				)
				(layer "B.Cu"
					(shape circle)
					(size 1.524 1.524)
					(clearance -0.0508)
				)
			)
		)
		(pad "2" thru_hole circle
			(at 1.27 -1.27 270)
			(size 1.524 1.524)
			(drill 0.9144)
			(layers "*.Cu" "*.Mask")
			(remove_unused_layers no)
			(net "L14_73OHM_6INCH_DN")
			(clearance -0.0508)
			(thermal_gap 0.127)
			(padstack
				(mode front_inner_back)
				(layer "Inner"
					(shape circle)
					(size 1.1684 1.1684)
					(clearance 0.127)
				)
				(layer "B.Cu"
					(shape circle)
					(size 1.524 1.524)
					(clearance -0.0508)
				)
			)
		)
		(pad "GND1" thru_hole rect
			(at -1.27 1.27 270)
			(size 1.524 1.524)
			(drill 0.9144)
			(layers "*.Cu" "*.Mask")
			(remove_unused_layers no)
			(net "GND")
			(clearance -0.0508)
			(thermal_gap 0.127)
			(padstack
				(mode front_inner_back)
				(layer "Inner"
					(shape circle)
					(size 1.1684 1.1684)
					(clearance 0.127)
				)
				(layer "B.Cu"
					(shape rect)
					(size 1.524 1.524)
					(clearance -0.0508)
				)
			)
		)
		(pad "GND2" thru_hole rect
			(at 1.27 1.27 270)
			(size 1.524 1.524)
			(drill 0.9144)
			(layers "*.Cu" "*.Mask")
			(remove_unused_layers no)
			(net "GND")
			(clearance -0.0508)
			(thermal_gap 0.127)
			(padstack
				(mode front_inner_back)
				(layer "Inner"
					(shape circle)
					(size 1.1684 1.1684)
					(clearance 0.127)
				)
				(layer "B.Cu"
					(shape rect)
					(size 1.524 1.524)
					(clearance -0.0508)
				)
			)
		)
	)
	(footprint ""
		(layer "F.Cu")
		(at 27.888946 -75.024742 90)
		(property "Reference" "C1D20"
			(at 0 0 90)
			(layer "F.SilkS")
			(hide yes)
			(effects
				(font
					(size 1.27 1.27)
				)
			)
		)
		(property "Value" ""
			(at 0 0 90)
			(layer "F.Fab")
			(effects
				(font
					(size 1.27 1.27)
				)
			)
		)
		(duplicate_pad_numbers_are_jumpers no)
		(fp_rect
			(start -0.3048 0.9906)
			(end 0.3048 -0.1016)
			(stroke
				(width 0)
				(type default)
			)
			(fill no)
			(layer "F.CrtYd")
		)
		(fp_line
			(start 0.3048 -0.1016)
			(end -0.3048 -0.1016)
			(stroke
				(width 0.1)
				(type default)
			)
			(layer "F.Fab")
		)
		(fp_line
			(start -0.3048 -0.1016)
			(end -0.3048 0.9906)
			(stroke
				(width 0.1)
				(type default)
			)
			(layer "F.Fab")
		)
		(fp_line
			(start 0.3048 0.9906)
			(end 0.3048 -0.1016)
			(stroke
				(width 0.1)
				(type default)
			)
			(layer "F.Fab")
		)
		(fp_line
			(start -0.3048 0.9906)
			(end 0.3048 0.9906)
			(stroke
				(width 0.1)
				(type default)
			)
			(layer "F.Fab")
		)
		(pad "1" smd rect
			(at 0 0 90)
			(size 0.508 0.508)
			(layers "F.Cu" "F.Mask" "F.Paste")
			(net "VR_PVCCIN_CPU1_PH3_BOOT")
		)
		(pad "2" smd rect
			(at 0 0.889 90)
			(size 0.508 0.508)
			(layers "F.Cu" "F.Mask" "F.Paste")
			(net "VR_PVCCIN_CPU1_PH3_PHASE")
		)
		(zone
			(layer "F.Cu")
			(hatch none 0.5)
			(connect_pads
				(clearance 0)
			)
			(min_thickness 0.25)
			(keepout
				(tracks allowed)
				(vias not_allowed)
				(pads allowed)
				(copperpour not_allowed)
				(footprints allowed)
			)
			(placement
				(enabled no)
				(sheetname "")
			)
			(fill
				(thermal_gap 0.5)
				(thermal_bridge_width 0.5)
				(island_removal_mode 0)
			)
			(polygon
				(pts
					(xy 28.523946 -74.770742) (xy 28.523946 -75.278742) (xy 28.142946 -75.278742) (xy 28.142946 -74.770742)
				)
			)
		)
		(zone
			(layer "F.Cu")
			(hatch none 0.5)
			(connect_pads
				(clearance 0)
			)
			(min_thickness 0.25)
			(keepout
				(tracks not_allowed)
				(vias allowed)
				(pads allowed)
				(copperpour not_allowed)
				(footprints allowed)
			)
			(placement
				(enabled no)
				(sheetname "")
			)
			(fill
				(thermal_gap 0.5)
				(thermal_bridge_width 0.5)
				(island_removal_mode 0)
			)
			(polygon
				(pts
					(xy 28.523946 -74.770742) (xy 28.523946 -75.278742) (xy 28.142946 -75.278742) (xy 28.142946 -74.770742)
				)
			)
		)
	)
)
